(kicad_pcb
	(version 20260206)
	(generator "pcbnew")
	(generator_version "10.0")
	(general
		(thickness 1.6)
		(legacy_teardrops no)
	)
	(paper "A4")
	(title_block
		(title "01162023_DA0F0TEBIF0_F0T_Expander_BD_F_brd_V02_OCP.brd")
		(comment 1 "Grand Teton / footprints 7457-7463 of 9728")
	)
	(layers
		(0 "F.Cu" signal "TOP")
		(4 "In1.Cu" signal "GND")
		(6 "In2.Cu" signal "VCC")
		(8 "In3.Cu" signal "VCC1")
		(10 "In4.Cu" signal "GND1")
		(12 "In5.Cu" signal "IN1")
		(14 "In6.Cu" signal "GND2")
		(16 "In7.Cu" signal "IN2")
		(18 "In8.Cu" signal "GND3")
		(20 "In9.Cu" signal "IN3")
		(22 "In10.Cu" signal "GND4")
		(24 "In11.Cu" signal "IN4")
		(26 "In12.Cu" signal "GND5")
		(28 "In13.Cu" signal "IN5")
		(30 "In14.Cu" signal "GND6")
		(32 "In15.Cu" signal "IN6")
		(34 "In16.Cu" signal "GND7")
		(2 "B.Cu" signal "BOTTOM")
		(9 "F.Adhes" user "F.Adhesive")
		(11 "B.Adhes" user "B.Adhesive")
		(13 "F.Paste" user "Package Geometry/Pastemask Top")
		(15 "B.Paste" user "Package Geometry/Pastemask Bottom")
		(5 "F.SilkS" user "Ref Des/Silkscreen Top")
		(7 "B.SilkS" user "Ref Des/Silkscreen Bottom")
		(1 "F.Mask" user "Board Geometry/Soldermask Top")
		(3 "B.Mask" user "Board Geometry/Soldermask Bottom")
		(17 "Dwgs.User" user "User.Drawings")
		(19 "Cmts.User" user "User.Comments")
		(21 "Eco1.User" user "User.Eco1")
		(23 "Eco2.User" user "User.Eco2")
		(25 "Edge.Cuts" user "Board Geometry/Outline")
		(27 "Margin" user)
		(31 "F.CrtYd" user "Package Geometry/Place Bound Top")
		(29 "B.CrtYd" user "Package Geometry/Place Bound Bottom")
		(35 "F.Fab" user "Ref Des/Assembly Top")
		(33 "B.Fab" user "Ref Des/Assembly Bottom")
	)
	(footprint ""
		(layer "B.Cu")
		(at 261.31393 -242.372388)
		(property "Reference" "R6581"
			(at 0 0 0)
			(layer "B.SilkS")
			(hide yes)
			(effects
				(font
					(size 1.27 1.27)
				)
				(justify mirror)
			)
		)
		(property "Value" ""
			(at 0 0 0)
			(layer "B.Fab")
			(effects
				(font
					(size 1.27 1.27)
				)
				(justify mirror)
			)
		)
		(duplicate_pad_numbers_are_jumpers no)
		(fp_line
			(start -0.7874 -0.4064)
			(end -0.7874 0.4064)
			(stroke
				(width 0.1524)
				(type default)
			)
			(layer "B.SilkS")
		)
		(fp_line
			(start -0.7874 0.4064)
			(end 0.7874 0.4064)
			(stroke
				(width 0.1524)
				(type default)
			)
			(layer "B.SilkS")
		)
		(fp_line
			(start 0.7874 -0.4064)
			(end -0.7874 -0.4064)
			(stroke
				(width 0.1524)
				(type default)
			)
			(layer "B.SilkS")
		)
		(fp_line
			(start 0.7874 0.4064)
			(end 0.7874 -0.4064)
			(stroke
				(width 0.1524)
				(type default)
			)
			(layer "B.SilkS")
		)
		(fp_line
			(start -0.67945 -0.3048)
			(end -0.67945 0.3048)
			(stroke
				(width 0.1)
				(type default)
			)
			(layer "B.Fab")
		)
		(fp_line
			(start -0.67945 0.3048)
			(end -0.120396 0.3048)
			(stroke
				(width 0.1)
				(type default)
			)
			(layer "B.Fab")
		)
		(fp_line
			(start -0.12065 -0.3048)
			(end -0.67945 -0.3048)
			(stroke
				(width 0.1)
				(type default)
			)
			(layer "B.Fab")
		)
		(fp_line
			(start -0.12065 -0.2794)
			(end -0.12065 -0.3048)
			(stroke
				(width 0.1)
				(type default)
			)
			(layer "B.Fab")
		)
		(fp_line
			(start -0.120396 0.2794)
			(end 0.12065 0.2794)
			(stroke
				(width 0.1)
				(type default)
			)
			(layer "B.Fab")
		)
		(fp_line
			(start -0.120396 0.3048)
			(end -0.120396 0.2794)
			(stroke
				(width 0.1)
				(type default)
			)
			(layer "B.Fab")
		)
		(fp_line
			(start 0.12065 -0.305054)
			(end 0.12065 -0.2794)
			(stroke
				(width 0.1)
				(type default)
			)
			(layer "B.Fab")
		)
		(fp_line
			(start 0.12065 -0.2794)
			(end -0.12065 -0.2794)
			(stroke
				(width 0.1)
				(type default)
			)
			(layer "B.Fab")
		)
		(fp_line
			(start 0.12065 0.2794)
			(end 0.12065 0.3048)
			(stroke
				(width 0.1)
				(type default)
			)
			(layer "B.Fab")
		)
		(fp_line
			(start 0.12065 0.3048)
			(end 0.67945 0.3048)
			(stroke
				(width 0.1)
				(type default)
			)
			(layer "B.Fab")
		)
		(fp_line
			(start 0.67945 -0.305054)
			(end 0.12065 -0.305054)
			(stroke
				(width 0.1)
				(type default)
			)
			(layer "B.Fab")
		)
		(fp_line
			(start 0.67945 0.3048)
			(end 0.67945 -0.305054)
			(stroke
				(width 0.1)
				(type default)
			)
			(layer "B.Fab")
		)
		(pad "1" smd circle
			(at 0.40005 0 180)
			(size 0 0)
			(layers "B.Cu" "B.Mask" "B.Paste")
			(net "P3V3_AUX")
		)
		(pad "2" smd circle
			(at -0.40005 0 180)
			(size 0 0)
			(layers "B.Cu" "B.Mask" "B.Paste")
			(net "PWRGD_PEX2_P1V8_PLL")
		)
	)
	(footprint ""
		(layer "B.Cu")
		(at 370.921534 -236.689392 180)
		(property "Reference" "U97"
			(at 0.112776 -2.450338 0)
			(unlocked yes)
			(layer "B.SilkS")
			(effects
				(font
					(size 0.7874 0.5842)
					(thickness 0.1524)
				)
				(justify mirror)
			)
		)
		(property "Value" ""
			(at 0 0 0)
			(layer "B.Fab")
			(effects
				(font
					(size 1.27 1.27)
				)
				(justify mirror)
			)
		)
		(duplicate_pad_numbers_are_jumpers no)
		(fp_line
			(start 2.085848 1.549908)
			(end 2.085848 -1.549908)
			(stroke
				(width 0.1524)
				(type default)
			)
			(layer "B.SilkS")
		)
		(fp_line
			(start 2.085848 -1.549908)
			(end 0.695198 -1.549908)
			(stroke
				(width 0.1524)
				(type default)
			)
			(layer "B.SilkS")
		)
		(fp_line
			(start 0.695198 -1.549908)
			(end 0 -0.85471)
			(stroke
				(width 0.1524)
				(type default)
			)
			(layer "B.SilkS")
		)
		(fp_line
			(start 0 -0.85471)
			(end -0.695198 -1.549908)
			(stroke
				(width 0.1524)
				(type default)
			)
			(layer "B.SilkS")
		)
		(fp_line
			(start -0.695198 -1.549908)
			(end -2.085848 -1.549908)
			(stroke
				(width 0.1524)
				(type default)
			)
			(layer "B.SilkS")
		)
		(fp_line
			(start -2.085848 1.549908)
			(end 2.085848 1.549908)
			(stroke
				(width 0.1524)
				(type default)
			)
			(layer "B.SilkS")
		)
		(fp_line
			(start -2.085848 -1.549908)
			(end -2.085848 1.549908)
			(stroke
				(width 0.1524)
				(type default)
			)
			(layer "B.SilkS")
		)
		(fp_poly
			(pts
				(xy 3.432048 -1.45796) (xy 3.432048 -0.44196) (xy 2.416048 -0.94996)
			)
			(stroke
				(width 0)
				(type default)
			)
			(fill yes)
			(layer "B.SilkS")
		)
		(fp_line
			(start 0.899922 1.549908)
			(end 0.899922 -1.549908)
			(stroke
				(width 0.1)
				(type default)
			)
			(layer "B.Fab")
		)
		(fp_line
			(start 0.899922 -1.549908)
			(end -0.899922 -1.549908)
			(stroke
				(width 0.1)
				(type default)
			)
			(layer "B.Fab")
		)
		(fp_line
			(start -0.899922 1.549908)
			(end 0.899922 1.549908)
			(stroke
				(width 0.1)
				(type default)
			)
			(layer "B.Fab")
		)
		(fp_line
			(start -0.899922 -1.549908)
			(end -0.899922 1.549908)
			(stroke
				(width 0.1)
				(type default)
			)
			(layer "B.Fab")
		)
		(fp_poly
			(pts
				(xy 3.432048 -1.45796) (xy 3.432048 -0.44196) (xy 2.416048 -0.94996)
			)
			(stroke
				(width 0)
				(type default)
			)
			(fill yes)
			(layer "B.Fab")
		)
		(pad "1" smd rect
			(at 1.400048 -0.94996 90)
			(size 0.6096 1.1176)
			(layers "B.Cu" "B.Mask" "B.Paste")
			(net "FT4232_SDB_EEPROM_DO")
		)
		(pad "2" smd rect
			(at 1.400048 0 90)
			(size 0.6096 1.1176)
			(layers "B.Cu" "B.Mask" "B.Paste")
			(net "GND")
		)
		(pad "3" smd rect
			(at 1.400048 0.94996 90)
			(size 0.6096 1.1176)
			(layers "B.Cu" "B.Mask" "B.Paste")
			(net "FT4232_SDB_EEPROM_R_SDA")
		)
		(pad "4" smd rect
			(at -1.400048 0.94996 90)
			(size 0.6096 1.1176)
			(layers "B.Cu" "B.Mask" "B.Paste")
			(net "FT4232_SDB_EEPROM_R_SCL")
		)
		(pad "5" smd rect
			(at -1.400048 0 90)
			(size 0.6096 1.1176)
			(layers "B.Cu" "B.Mask" "B.Paste")
			(net "FT4232_SDB_EEPROM_R_CS")
		)
		(pad "6" smd rect
			(at -1.400048 -0.94996 90)
			(size 0.6096 1.1176)
			(layers "B.Cu" "B.Mask" "B.Paste")
			(net "P3V3_AUX")
		)
	)
	(footprint ""
		(layer "B.Cu")
		(at 411.274768 -293.99992 90)
		(property "Reference" "C1910"
			(at 0 0 90)
			(layer "B.SilkS")
			(hide yes)
			(effects
				(font
					(size 1.27 1.27)
				)
				(justify mirror)
			)
		)
		(property "Value" ""
			(at 0 0 90)
			(layer "B.Fab")
			(effects
				(font
					(size 1.27 1.27)
				)
				(justify mirror)
			)
		)
		(duplicate_pad_numbers_are_jumpers no)
		(fp_line
			(start 0.299974 -0.150114)
			(end -0.299974 -0.150114)
			(stroke
				(width 0.1)
				(type default)
			)
			(layer "B.Fab")
		)
		(fp_line
			(start -0.299974 -0.150114)
			(end -0.299974 0.150114)
			(stroke
				(width 0.1)
				(type default)
			)
			(layer "B.Fab")
		)
		(fp_line
			(start 0.299974 0.150114)
			(end 0.299974 -0.150114)
			(stroke
				(width 0.1)
				(type default)
			)
			(layer "B.Fab")
		)
		(fp_line
			(start -0.299974 0.150114)
			(end 0.299974 0.150114)
			(stroke
				(width 0.1)
				(type default)
			)
			(layer "B.Fab")
		)
		(pad "1" smd rect
			(at 0.2667 0 270)
			(size 0.3048 0.381)
			(layers "B.Cu" "B.Mask" "B.Paste")
			(net "P0V8_PEX3")
		)
		(pad "2" smd rect
			(at -0.2667 0 270)
			(size 0.3048 0.381)
			(layers "B.Cu" "B.Mask" "B.Paste")
			(net "GND")
		)
	)
	(footprint ""
		(layer "B.Cu")
		(at 128.241044 -181.03977)
		(property "Reference" "C2660"
			(at 0 0 0)
			(layer "B.SilkS")
			(hide yes)
			(effects
				(font
					(size 1.27 1.27)
				)
				(justify mirror)
			)
		)
		(property "Value" ""
			(at 0 0 0)
			(layer "B.Fab")
			(effects
				(font
					(size 1.27 1.27)
				)
				(justify mirror)
			)
		)
		(duplicate_pad_numbers_are_jumpers no)
		(fp_line
			(start -0.7874 -0.4064)
			(end -0.7874 0.4064)
			(stroke
				(width 0.1524)
				(type default)
			)
			(layer "B.SilkS")
		)
		(fp_line
			(start -0.7874 0.4064)
			(end 0.7874 0.4064)
			(stroke
				(width 0.1524)
				(type default)
			)
			(layer "B.SilkS")
		)
		(fp_line
			(start 0.7874 -0.4064)
			(end -0.7874 -0.4064)
			(stroke
				(width 0.1524)
				(type default)
			)
			(layer "B.SilkS")
		)
		(fp_line
			(start 0.7874 0.4064)
			(end 0.7874 -0.4064)
			(stroke
				(width 0.1524)
				(type default)
			)
			(layer "B.SilkS")
		)
		(fp_line
			(start -0.67945 -0.3048)
			(end -0.67945 0.3048)
			(stroke
				(width 0.1)
				(type default)
			)
			(layer "B.Fab")
		)
		(fp_line
			(start -0.67945 0.3048)
			(end -0.120396 0.3048)
			(stroke
				(width 0.1)
				(type default)
			)
			(layer "B.Fab")
		)
		(fp_line
			(start -0.12065 -0.3048)
			(end -0.67945 -0.3048)
			(stroke
				(width 0.1)
				(type default)
			)
			(layer "B.Fab")
		)
		(fp_line
			(start -0.12065 -0.2794)
			(end -0.12065 -0.3048)
			(stroke
				(width 0.1)
				(type default)
			)
			(layer "B.Fab")
		)
		(fp_line
			(start -0.120396 0.2794)
			(end 0.12065 0.2794)
			(stroke
				(width 0.1)
				(type default)
			)
			(layer "B.Fab")
		)
		(fp_line
			(start -0.120396 0.3048)
			(end -0.120396 0.2794)
			(stroke
				(width 0.1)
				(type default)
			)
			(layer "B.Fab")
		)
		(fp_line
			(start 0.12065 -0.305054)
			(end 0.12065 -0.2794)
			(stroke
				(width 0.1)
				(type default)
			)
			(layer "B.Fab")
		)
		(fp_line
			(start 0.12065 -0.2794)
			(end -0.12065 -0.2794)
			(stroke
				(width 0.1)
				(type default)
			)
			(layer "B.Fab")
		)
		(fp_line
			(start 0.12065 0.2794)
			(end 0.12065 0.3048)
			(stroke
				(width 0.1)
				(type default)
			)
			(layer "B.Fab")
		)
		(fp_line
			(start 0.12065 0.3048)
			(end 0.67945 0.3048)
			(stroke
				(width 0.1)
				(type default)
			)
			(layer "B.Fab")
		)
		(fp_line
			(start 0.67945 -0.305054)
			(end 0.12065 -0.305054)
			(stroke
				(width 0.1)
				(type default)
			)
			(layer "B.Fab")
		)
		(fp_line
			(start 0.67945 0.3048)
			(end 0.67945 -0.305054)
			(stroke
				(width 0.1)
				(type default)
			)
			(layer "B.Fab")
		)
		(pad "1" smd circle
			(at 0.40005 0 180)
			(size 0 0)
			(layers "B.Cu" "B.Mask" "B.Paste")
			(net "P3V3_DB2000QL_VDD")
		)
		(pad "2" smd circle
			(at -0.40005 0 180)
			(size 0 0)
			(layers "B.Cu" "B.Mask" "B.Paste")
			(net "GND")
		)
	)
	(footprint ""
		(layer "B.Cu")
		(at 338.64169 -293.660068 90)
		(property "Reference" "PC165"
			(at 0 0 90)
			(layer "B.SilkS")
			(hide yes)
			(effects
				(font
					(size 1.27 1.27)
				)
				(justify mirror)
			)
		)
		(property "Value" ""
			(at 0 0 90)
			(layer "B.Fab")
			(effects
				(font
					(size 1.27 1.27)
				)
				(justify mirror)
			)
		)
		(duplicate_pad_numbers_are_jumpers no)
		(fp_line
			(start 4.84378 -2.150618)
			(end 4.53898 -2.150618)
			(stroke
				(width 0.1524)
				(type default)
			)
			(layer "B.SilkS")
		)
		(fp_line
			(start 4.84378 -2.150618)
			(end 4.842256 2.163064)
			(stroke
				(width 0.1524)
				(type default)
			)
			(layer "B.SilkS")
		)
		(fp_line
			(start 4.69138 -2.150618)
			(end 4.692396 2.161032)
			(stroke
				(width 0.1524)
				(type default)
			)
			(layer "B.SilkS")
		)
		(fp_line
			(start 4.53898 -2.150618)
			(end 4.539742 2.152142)
			(stroke
				(width 0.1524)
				(type default)
			)
			(layer "B.SilkS")
		)
		(fp_line
			(start 4.53898 -2.15011)
			(end -4.53898 -2.15011)
			(stroke
				(width 0.1524)
				(type default)
			)
			(layer "B.SilkS")
		)
		(fp_line
			(start -4.53898 -2.15011)
			(end -4.53898 2.15011)
			(stroke
				(width 0.1524)
				(type default)
			)
			(layer "B.SilkS")
		)
		(fp_line
			(start 4.53898 2.15011)
			(end 4.53898 -2.15011)
			(stroke
				(width 0.1524)
				(type default)
			)
			(layer "B.SilkS")
		)
		(fp_line
			(start -4.53898 2.15011)
			(end 4.53898 2.15011)
			(stroke
				(width 0.1524)
				(type default)
			)
			(layer "B.SilkS")
		)
		(fp_line
			(start 4.83108 2.150364)
			(end 4.447794 2.149348)
			(stroke
				(width 0.1524)
				(type default)
			)
			(layer "B.SilkS")
		)
		(fp_line
			(start 3.64998 -2.15011)
			(end -3.64998 -2.15011)
			(stroke
				(width 0.1)
				(type default)
			)
			(layer "B.Fab")
		)
		(fp_line
			(start -3.64998 -2.15011)
			(end -3.64998 2.15011)
			(stroke
				(width 0.1)
				(type default)
			)
			(layer "B.Fab")
		)
		(fp_line
			(start 3.64998 2.15011)
			(end 3.64998 -2.15011)
			(stroke
				(width 0.1)
				(type default)
			)
			(layer "B.Fab")
		)
		(fp_line
			(start -3.64998 2.15011)
			(end 3.64998 2.15011)
			(stroke
				(width 0.1)
				(type default)
			)
			(layer "B.Fab")
		)
		(fp_text user "+"
			(at 6.214872 -0.337058 90)
			(unlocked yes)
			(layer "B.SilkS")
			(effects
				(font
					(size 1.905 1.4224)
					(thickness 0.1524)
				)
				(justify left mirror)
			)
		)
		(fp_text user "-"
			(at -4.313174 -0.094488 90)
			(unlocked yes)
			(layer "B.SilkS")
			(effects
				(font
					(size 1.905 1.4224)
					(thickness 0.1524)
				)
				(justify left mirror)
			)
		)
		(fp_text user "+"
			(at 6.214872 -0.337058 90)
			(unlocked yes)
			(layer "B.Fab")
			(effects
				(font
					(size 1.905 1.4224)
					(thickness 0.1524)
				)
				(justify left mirror)
			)
		)
		(fp_text user "-"
			(at -4.313174 -0.094488 90)
			(unlocked yes)
			(layer "B.Fab")
			(effects
				(font
					(size 1.905 1.4224)
					(thickness 0.1524)
				)
				(justify left mirror)
			)
		)
		(pad "1" smd rect
			(at 3.199892 0 270)
			(size 2.413 2.8194)
			(layers "B.Cu" "B.Mask" "B.Paste")
			(net "P0V8_PEX2")
		)
		(pad "2" smd rect
			(at -3.199892 0 270)
			(size 2.413 2.8194)
			(layers "B.Cu" "B.Mask" "B.Paste")
			(net "GND")
		)
	)
	(footprint ""
		(layer "B.Cu")
		(at 333.171546 -317.143384 90)
		(property "Reference" "C4304"
			(at 0 0 90)
			(layer "B.SilkS")
			(hide yes)
			(effects
				(font
					(size 1.27 1.27)
				)
				(justify mirror)
			)
		)
		(property "Value" ""
			(at 0 0 90)
			(layer "B.Fab")
			(effects
				(font
					(size 1.27 1.27)
				)
				(justify mirror)
			)
		)
		(duplicate_pad_numbers_are_jumpers no)
		(fp_line
			(start 1.2954 -0.5842)
			(end -1.2954 -0.5842)
			(stroke
				(width 0.1524)
				(type default)
			)
			(layer "B.SilkS")
		)
		(fp_line
			(start -1.2954 -0.5842)
			(end -1.2954 0.5842)
			(stroke
				(width 0.1524)
				(type default)
			)
			(layer "B.SilkS")
		)
		(fp_line
			(start 1.2954 0.5842)
			(end 1.2954 -0.5842)
			(stroke
				(width 0.1524)
				(type default)
			)
			(layer "B.SilkS")
		)
		(fp_line
			(start -1.2954 0.5842)
			(end 1.2954 0.5842)
			(stroke
				(width 0.1524)
				(type default)
			)
			(layer "B.SilkS")
		)
		(fp_line
			(start 0.8636 -0.4572)
			(end -0.8636 -0.4572)
			(stroke
				(width 0.1)
				(type default)
			)
			(layer "B.Fab")
		)
		(fp_line
			(start -0.8636 -0.4572)
			(end -0.8636 -0.4064)
			(stroke
				(width 0.1)
				(type default)
			)
			(layer "B.Fab")
		)
		(fp_line
			(start 1.1938 -0.4064)
			(end 0.8636 -0.4064)
			(stroke
				(width 0.1)
				(type default)
			)
			(layer "B.Fab")
		)
		(fp_line
			(start 0.8636 -0.4064)
			(end 0.8636 -0.4572)
			(stroke
				(width 0.1)
				(type default)
			)
			(layer "B.Fab")
		)
		(fp_line
			(start -0.8636 -0.4064)
			(end -1.1938 -0.4064)
			(stroke
				(width 0.1)
				(type default)
			)
			(layer "B.Fab")
		)
		(fp_line
			(start -1.1938 -0.4064)
			(end -1.1938 0.4064)
			(stroke
				(width 0.1)
				(type default)
			)
			(layer "B.Fab")
		)
		(fp_line
			(start 1.1938 0.4064)
			(end 1.1938 -0.4064)
			(stroke
				(width 0.1)
				(type default)
			)
			(layer "B.Fab")
		)
		(fp_line
			(start 0.8636 0.4064)
			(end 1.1938 0.4064)
			(stroke
				(width 0.1)
				(type default)
			)
			(layer "B.Fab")
		)
		(fp_line
			(start -0.8636 0.4064)
			(end -0.8636 0.4572)
			(stroke
				(width 0.1)
				(type default)
			)
			(layer "B.Fab")
		)
		(fp_line
			(start -1.1938 0.4064)
			(end -0.8636 0.4064)
			(stroke
				(width 0.1)
				(type default)
			)
			(layer "B.Fab")
		)
		(fp_line
			(start 0.8636 0.4572)
			(end 0.8636 0.4064)
			(stroke
				(width 0.1)
				(type default)
			)
			(layer "B.Fab")
		)
		(fp_line
			(start -0.8636 0.4572)
			(end 0.8636 0.4572)
			(stroke
				(width 0.1)
				(type default)
			)
			(layer "B.Fab")
		)
		(pad "1" smd rect
			(at 0.7366 0)
			(size 0.7112 0.8128)
			(layers "B.Cu" "B.Mask" "B.Paste")
			(net "P0V8_PEX2")
		)
		(pad "2" smd rect
			(at -0.7366 0)
			(size 0.7112 0.8128)
			(layers "B.Cu" "B.Mask" "B.Paste")
			(net "GND")
		)
	)
	(footprint ""
		(layer "B.Cu")
		(at 283.774896 -297.79976 90)
		(property "Reference" "C1660"
			(at 0 0 90)
			(layer "B.SilkS")
			(hide yes)
			(effects
				(font
					(size 1.27 1.27)
				)
				(justify mirror)
			)
		)
		(property "Value" ""
			(at 0 0 90)
			(layer "B.Fab")
			(effects
				(font
					(size 1.27 1.27)
				)
				(justify mirror)
			)
		)
		(duplicate_pad_numbers_are_jumpers no)
		(fp_line
			(start 0.299974 -0.150114)
			(end -0.299974 -0.150114)
			(stroke
				(width 0.1)
				(type default)
			)
			(layer "B.Fab")
		)
		(fp_line
			(start -0.299974 -0.150114)
			(end -0.299974 0.150114)
			(stroke
				(width 0.1)
				(type default)
			)
			(layer "B.Fab")
		)
		(fp_line
			(start 0.299974 0.150114)
			(end 0.299974 -0.150114)
			(stroke
				(width 0.1)
				(type default)
			)
			(layer "B.Fab")
		)
		(fp_line
			(start -0.299974 0.150114)
			(end 0.299974 0.150114)
			(stroke
				(width 0.1)
				(type default)
			)
			(layer "B.Fab")
		)
		(pad "1" smd rect
			(at 0.2667 0 270)
			(size 0.3048 0.381)
			(layers "B.Cu" "B.Mask" "B.Paste")
			(net "P0V8_PEX2")
		)
		(pad "2" smd rect
			(at -0.2667 0 270)
			(size 0.3048 0.381)
			(layers "B.Cu" "B.Mask" "B.Paste")
			(net "GND")
		)
	)
)
